(kicad_pcb
	(version 20221018)
	(generator pcbnew)
	(general
    (thickness 1.518)
  )
	(paper "A4")
	(title_block
    (title "Kria K26 Devboard")
    (date "2024-03-26")
    (rev "1.2.5")
    (comment 1 "www.antmicro.com")
    (comment 2 "Antmicro Ltd.")
		(comment 9 "footprints 134-139 of 660")
	)
	(layers
    (0 "F.Cu" mixed)
    (1 "In1.Cu" power)
    (2 "In2.Cu" mixed)
    (3 "In3.Cu" power)
    (4 "In4.Cu" mixed)
    (5 "In5.Cu" power)
    (6 "In6.Cu" mixed)
    (31 "B.Cu" power)
    (32 "B.Adhes" user "B.Adhesive")
    (33 "F.Adhes" user "F.Adhesive")
    (34 "B.Paste" user)
    (35 "F.Paste" user)
    (36 "B.SilkS" user "B.Silkscreen")
    (37 "F.SilkS" user "F.Silkscreen")
    (38 "B.Mask" user)
    (39 "F.Mask" user)
    (40 "Dwgs.User" user "User.Drawings")
    (41 "Cmts.User" user "User.Comments")
    (42 "Eco1.User" user "User.Eco1")
    (43 "Eco2.User" user "User.Eco2")
    (44 "Edge.Cuts" user)
    (45 "Margin" user)
    (46 "B.CrtYd" user "B.Courtyard")
    (47 "F.CrtYd" user "F.Courtyard")
    (48 "B.Fab" user)
    (49 "F.Fab" user)
  )
	(footprint "kria-k26-devboard-footprints:C_0402_1005Metric" (layer "F.Cu")
    (at 116.9 123.55)
    (descr "Capacitor SMD 0402")
    (tags "capacitor SMD 0402")
    (property "Author" "Antmicro")
    (property "Dielectric" "X5R")
    (property "License" "Apache-2.0")
    (property "MPN" "GRM155R61H104KE14D")
    (property "Manufacturer" "Murata")
    (property "Sheetfile" "clock.kicad_sch")
    (property "Sheetname" "Clock distribution")
    (property "Val" "100n")
    (property "Voltage" "50V")
    (property "ki_description" " ")
    (attr smd)
    (fp_text reference "C24" (at -1 1.19) (layer "F.SilkS")
        (effects (font (size 0.7 0.7) (thickness 0.15)) (justify left bottom))
    )
    (fp_text value "C_100n_0402" (at 0 1.4) (layer "F.Fab") hide
        (effects (font (size 0.7 0.7) (thickness 0.15)) (justify left bottom))
    )
    (fp_text user "License: Apache-2.0" (at -0.932 5.17) (layer "F.Fab") hide
        (effects (font (size 0.7 0.7) (thickness 0.15)) (justify left bottom))
    )
    (fp_text user "Author: Antmicro" (at -0.932 4.17) (layer "F.Fab") hide
        (effects (font (size 0.7 0.7) (thickness 0.15)) (justify left bottom))
    )
    (fp_text user "${REFERENCE}" (at -0.932 3.168) (layer "F.Fab") hide
        (effects (font (size 0.7 0.7) (thickness 0.15)) (justify left bottom))
    )
    (fp_rect (start -0.94 -0.47) (end 0.94 0.47)
      (stroke (width 0.05) (type solid)) (fill none) (layer "F.CrtYd"))
    (fp_rect (start -0.499 -0.249) (end 0.499 0.249)
      (stroke (width 0.15) (type solid)) (fill none) (layer "F.Fab"))
    (pad "1" smd roundrect (at -0.484 0) (size 0.59 0.64) (layers "F.Cu" "F.Paste" "F.Mask") (roundrect_rratio 0.25)
      (net 15 "PS_3V3") (pintype "passive"))
    (pad "2" smd roundrect (at 0.484 0) (size 0.59 0.64) (layers "F.Cu" "F.Paste" "F.Mask") (roundrect_rratio 0.25)
      (net 1 "GND") (pintype "passive"))
  )
	(footprint "kria-k26-devboard-footprints:C_0402_1005Metric" (layer "F.Cu")
    (at 129.95 79.8)
    (descr "Capacitor SMD 0402")
    (tags "capacitor SMD 0402")
    (property "Author" "Antmicro")
    (property "Dielectric" "X5R")
    (property "License" "Apache-2.0")
    (property "MPN" "GRM155R61H104KE14D")
    (property "Manufacturer" "Murata")
    (property "Sheetfile" "usb.kicad_sch")
    (property "Sheetname" "USB")
    (property "Val" "100n")
    (property "Voltage" "50V")
    (property "ki_description" " ")
    (attr smd)
    (fp_text reference "C56" (at 0.84 0.37) (layer "F.SilkS")
        (effects (font (size 0.7 0.7) (thickness 0.15)) (justify left bottom))
    )
    (fp_text value "C_100n_0402" (at 0 1.4) (layer "F.Fab") hide
        (effects (font (size 0.7 0.7) (thickness 0.15)) (justify left bottom))
    )
    (fp_text user "License: Apache-2.0" (at -0.932 5.17) (layer "F.Fab") hide
        (effects (font (size 0.7 0.7) (thickness 0.15)) (justify left bottom))
    )
    (fp_text user "Author: Antmicro" (at -0.932 4.17) (layer "F.Fab") hide
        (effects (font (size 0.7 0.7) (thickness 0.15)) (justify left bottom))
    )
    (fp_text user "${REFERENCE}" (at -0.932 3.168) (layer "F.Fab") hide
        (effects (font (size 0.7 0.7) (thickness 0.15)) (justify left bottom))
    )
    (fp_rect (start -0.94 -0.47) (end 0.94 0.47)
      (stroke (width 0.05) (type solid)) (fill none) (layer "F.CrtYd"))
    (fp_rect (start -0.499 -0.249) (end 0.499 0.249)
      (stroke (width 0.15) (type solid)) (fill none) (layer "F.Fab"))
    (pad "1" smd roundrect (at -0.484 0) (size 0.59 0.64) (layers "F.Cu" "F.Paste" "F.Mask") (roundrect_rratio 0.25)
      (net 18 "PS_1V2") (pintype "passive"))
    (pad "2" smd roundrect (at 0.484 0) (size 0.59 0.64) (layers "F.Cu" "F.Paste" "F.Mask") (roundrect_rratio 0.25)
      (net 1 "GND") (pintype "passive"))
  )
	(footprint "kria-k26-devboard-footprints:C_0402_1005Metric" (layer "F.Cu")
    (at 130.975 75.11 -90)
    (descr "Capacitor SMD 0402")
    (tags "capacitor SMD 0402")
    (property "Author" "Antmicro")
    (property "Dielectric" "X5R")
    (property "License" "Apache-2.0")
    (property "MPN" "GRM155R61H104KE14D")
    (property "Manufacturer" "Murata")
    (property "Sheetfile" "usb.kicad_sch")
    (property "Sheetname" "USB")
    (property "Val" "100n")
    (property "Voltage" "50V")
    (property "ki_description" " ")
    (attr smd)
    (fp_text reference "C69" (at 3.07 -0.405 -90) (layer "F.SilkS")
        (effects (font (size 0.7 0.7) (thickness 0.15)) (justify left bottom))
    )
    (fp_text value "C_100n_0402" (at 0 1.4 -90) (layer "F.Fab") hide
        (effects (font (size 0.7 0.7) (thickness 0.15)) (justify left bottom))
    )
    (fp_text user "${REFERENCE}" (at -0.932 3.168 -90) (layer "F.Fab") hide
        (effects (font (size 0.7 0.7) (thickness 0.15)) (justify left bottom))
    )
    (fp_text user "Author: Antmicro" (at -0.932 4.17 -90) (layer "F.Fab") hide
        (effects (font (size 0.7 0.7) (thickness 0.15)) (justify left bottom))
    )
    (fp_text user "License: Apache-2.0" (at -0.932 5.17 -90) (layer "F.Fab") hide
        (effects (font (size 0.7 0.7) (thickness 0.15)) (justify left bottom))
    )
    (fp_rect (start -0.94 -0.47) (end 0.94 0.47)
      (stroke (width 0.05) (type solid)) (fill none) (layer "F.CrtYd"))
    (fp_rect (start -0.499 -0.249) (end 0.499 0.249)
      (stroke (width 0.15) (type solid)) (fill none) (layer "F.Fab"))
    (pad "1" smd roundrect (at -0.484 0 270) (size 0.59 0.64) (layers "F.Cu" "F.Paste" "F.Mask") (roundrect_rratio 0.25)
      (net 281 "/USB/USB2_TX_C_P") (pintype "passive"))
    (pad "2" smd roundrect (at 0.484 0 270) (size 0.59 0.64) (layers "F.Cu" "F.Paste" "F.Mask") (roundrect_rratio 0.25)
      (net 63 "/USB/USB2_TX_P") (pintype "passive"))
  )
	(footprint "kria-k26-devboard-footprints:QFN-24-1EP_4x4mm_P0.5mm_EP2.6x2.6mm" (layer "F.Cu")
    (at 121.149 98.729 -90)
    (descr "QFN, 24 Pin (http://ww1.microchip.com/downloads/en/PackagingSpec/00000049BQ.pdf#page=278), generated with kicad-footprint-generator ipc_noLead_generator.py")
    (tags "QFN NoLead")
    (property "Author" "Antmicro")
    (property "License" "Apache-2.0")
    (property "MPN" "USB3310C-CP")
    (property "Manufacturer" "Microchip Technology")
    (property "Sheetfile" "usb.kicad_sch")
    (property "Sheetname" "USB")
    (property "ki_description" "USB interface")
    (property "ki_keywords" "SMT, IC")
    (attr smd)
    (fp_text reference "U23" (at -2.619 2.839) (layer "F.SilkS")
        (effects (font (size 0.7 0.7) (thickness 0.15)) (justify left bottom))
    )
    (fp_text value "USB3310C-CP" (at 0 3.4 -90) (layer "F.Fab") hide
        (effects (font (size 0.7 0.7) (thickness 0.15)) (justify left bottom))
    )
    (fp_text user "License: Apache-2.0" (at -2.503 6.6 -90) (layer "F.Fab") hide
        (effects (font (size 0.7 0.7) (thickness 0.15)) (justify left bottom))
    )
    (fp_text user "Author: Antmicro" (at -2.503 7.8 -90) (layer "F.Fab") hide
        (effects (font (size 0.7 0.7) (thickness 0.15)) (justify left bottom))
    )
    (fp_text user "${REFERENCE}" (at -2.503 5.4 -90) (layer "F.Fab") hide
        (effects (font (size 0.7 0.7) (thickness 0.15)) (justify left bottom))
    )
    (fp_line (start -2.11 -1.636) (end -2.11 -2.11)
      (stroke (width 0.15) (type solid)) (layer "F.SilkS"))
    (fp_line (start -2.11 2.108) (end -2.11 1.634)
      (stroke (width 0.15) (type solid)) (layer "F.SilkS"))
    (fp_line (start -1.635 -2.11) (end -2.11 -2.11)
      (stroke (width 0.15) (type solid)) (layer "F.SilkS"))
    (fp_line (start -1.635 2.108) (end -2.11 2.108)
      (stroke (width 0.15) (type solid)) (layer "F.SilkS"))
    (fp_line (start 1.634 -2.11) (end 2.108 -2.11)
      (stroke (width 0.15) (type solid)) (layer "F.SilkS"))
    (fp_line (start 1.634 2.108) (end 2.108 2.108)
      (stroke (width 0.15) (type solid)) (layer "F.SilkS"))
    (fp_line (start 2.108 -2.11) (end 2.108 -1.635)
      (stroke (width 0.15) (type solid)) (layer "F.SilkS"))
    (fp_line (start 2.108 2.108) (end 2.108 1.634)
      (stroke (width 0.15) (type solid)) (layer "F.SilkS"))
    (fp_circle (center -2.3 -2.3) (end -2.25 -2.3)
      (stroke (width 0.15) (type solid)) (fill solid) (layer "F.SilkS"))
    (fp_rect (start -2.503 -2.503) (end 2.5 2.5)
      (stroke (width 0.05) (type solid)) (fill none) (layer "F.CrtYd"))
    (fp_line (start -2 -1) (end -1 -2)
      (stroke (width 0.15) (type solid)) (layer "F.Fab"))
    (fp_line (start -2 1.999) (end -2 -1)
      (stroke (width 0.15) (type solid)) (layer "F.Fab"))
    (fp_line (start -1 -2) (end 1.999 -2)
      (stroke (width 0.15) (type solid)) (layer "F.Fab"))
    (fp_line (start 1.999 -2) (end 1.999 1.999)
      (stroke (width 0.15) (type solid)) (layer "F.Fab"))
    (fp_line (start 1.999 1.999) (end -2 1.999)
      (stroke (width 0.15) (type solid)) (layer "F.Fab"))
    (pad "" smd roundrect (at -0.652 -0.652 270) (size 1.05 1.05) (layers "F.Paste") (roundrect_rratio 0.238095))
    (pad "" smd roundrect (at -0.652 0.65 270) (size 1.05 1.05) (layers "F.Paste") (roundrect_rratio 0.238095))
    (pad "" smd roundrect (at 0.65 -0.652 270) (size 1.05 1.05) (layers "F.Paste") (roundrect_rratio 0.238095))
    (pad "" smd roundrect (at 0.65 0.65 270) (size 1.05 1.05) (layers "F.Paste") (roundrect_rratio 0.238095))
    (pad "1" smd roundrect (at -1.938 -1.25 270) (size 0.825 0.25) (layers "F.Cu" "F.Paste" "F.Mask") (roundrect_rratio 0.25)
      (net 1 "GND") (pinfunction "ID") (pintype "input"))
    (pad "2" smd roundrect (at -1.938 -0.75 270) (size 0.825 0.25) (layers "F.Cu" "F.Paste" "F.Mask") (roundrect_rratio 0.25)
      (net 669 "Net-(U23-VBUS)") (pinfunction "VBUS") (pintype "bidirectional"))
    (pad "3" smd roundrect (at -1.938 -0.25 270) (size 0.825 0.25) (layers "F.Cu" "F.Paste" "F.Mask") (roundrect_rratio 0.25)
      (net 8 "SOM_5V0") (pinfunction "VBAT") (pintype "power_in"))
    (pad "4" smd roundrect (at -1.938 0.248 270) (size 0.825 0.25) (layers "F.Cu" "F.Paste" "F.Mask") (roundrect_rratio 0.25)
      (net 154 "Net-(U23-VDD_3V3)") (pinfunction "VDD_3V3") (pintype "power_in"))
    (pad "5" smd roundrect (at -1.938 0.748 270) (size 0.825 0.25) (layers "F.Cu" "F.Paste" "F.Mask") (roundrect_rratio 0.25)
      (net 54 "/USB/USB2_PHY_N") (pinfunction "DM") (pintype "bidirectional"))
    (pad "6" smd roundrect (at -1.938 1.249 270) (size 0.825 0.25) (layers "F.Cu" "F.Paste" "F.Mask") (roundrect_rratio 0.25)
      (net 55 "/USB/USB2_PHY_P") (pinfunction "DP") (pintype "bidirectional"))
    (pad "7" smd roundrect (at -1.25 1.937 270) (size 0.25 0.825) (layers "F.Cu" "F.Paste" "F.Mask") (roundrect_rratio 0.25)
      (net 39 "/USB/MIO63") (pinfunction "DATA7") (pintype "bidirectional"))
    (pad "8" smd roundrect (at -0.75 1.937 270) (size 0.25 0.825) (layers "F.Cu" "F.Paste" "F.Mask") (roundrect_rratio 0.25)
      (net 38 "/USB/MIO62") (pinfunction "DATA6") (pintype "bidirectional"))
    (pad "9" smd roundrect (at -0.25 1.937 270) (size 0.25 0.825) (layers "F.Cu" "F.Paste" "F.Mask") (roundrect_rratio 0.25)
      (net 37 "/USB/MIO61") (pinfunction "DATA5") (pintype "bidirectional"))
    (pad "10" smd roundrect (at 0.248 1.937 270) (size 0.25 0.825) (layers "F.Cu" "F.Paste" "F.Mask") (roundrect_rratio 0.25)
      (net 42 "/USB/MIO60") (pinfunction "DATA4") (pintype "bidirectional"))
    (pad "11" smd roundrect (at 0.748 1.937 270) (size 0.25 0.825) (layers "F.Cu" "F.Paste" "F.Mask") (roundrect_rratio 0.25)
      (net 46 "/USB/MIO52") (pinfunction "CLKOUT") (pintype "output"))
    (pad "12" smd roundrect (at 1.249 1.937 270) (size 0.25 0.825) (layers "F.Cu" "F.Paste" "F.Mask") (roundrect_rratio 0.25)
      (net 41 "/USB/MIO59") (pinfunction "DATA3") (pintype "bidirectional"))
    (pad "13" smd roundrect (at 1.937 1.249 270) (size 0.825 0.25) (layers "F.Cu" "F.Paste" "F.Mask") (roundrect_rratio 0.25)
      (net 48 "/USB/MIO54") (pinfunction "DATA2") (pintype "bidirectional"))
    (pad "14" smd roundrect (at 1.937 0.748 270) (size 0.825 0.25) (layers "F.Cu" "F.Paste" "F.Mask") (roundrect_rratio 0.25)
      (net 17 "PS_1V8") (pinfunction "REFSEL1") (pintype "input"))
    (pad "15" smd roundrect (at 1.937 0.248 270) (size 0.825 0.25) (layers "F.Cu" "F.Paste" "F.Mask") (roundrect_rratio 0.25)
      (net 17 "PS_1V8") (pinfunction "REFSEL0") (pintype "input"))
    (pad "16" smd roundrect (at 1.937 -0.25 270) (size 0.825 0.25) (layers "F.Cu" "F.Paste" "F.Mask") (roundrect_rratio 0.25)
      (net 45 "/USB/MIO57") (pinfunction "DATA1") (pintype "bidirectional"))
    (pad "17" smd roundrect (at 1.937 -0.75 270) (size 0.825 0.25) (layers "F.Cu" "F.Paste" "F.Mask") (roundrect_rratio 0.25)
      (net 44 "/USB/MIO56") (pinfunction "DATA0") (pintype "bidirectional"))
    (pad "18" smd roundrect (at 1.937 -1.25 270) (size 0.825 0.25) (layers "F.Cu" "F.Paste" "F.Mask") (roundrect_rratio 0.25)
      (net 43 "/USB/MIO55") (pinfunction "NXT") (pintype "output"))
    (pad "19" smd roundrect (at 1.249 -1.938 270) (size 0.25 0.825) (layers "F.Cu" "F.Paste" "F.Mask") (roundrect_rratio 0.25)
      (net 47 "/USB/MIO53") (pinfunction "DIR") (pintype "output"))
    (pad "20" smd roundrect (at 0.748 -1.938 270) (size 0.25 0.825) (layers "F.Cu" "F.Paste" "F.Mask") (roundrect_rratio 0.25)
      (net 40 "/USB/MIO58") (pinfunction "STP") (pintype "input"))
    (pad "21" smd roundrect (at 0.248 -1.938 270) (size 0.25 0.825) (layers "F.Cu" "F.Paste" "F.Mask") (roundrect_rratio 0.25)
      (net 17 "PS_1V8") (pinfunction "VDD_1V8") (pintype "power_in"))
    (pad "22" smd roundrect (at -0.25 -1.938 270) (size 0.25 0.825) (layers "F.Cu" "F.Paste" "F.Mask") (roundrect_rratio 0.25)
      (net 178 "/Reset logic/~{USB_PHY_RESET}") (pinfunction "RESETB") (pintype "input"))
    (pad "23" smd roundrect (at -0.75 -1.938 270) (size 0.25 0.825) (layers "F.Cu" "F.Paste" "F.Mask") (roundrect_rratio 0.25)
      (net 277 "/USB/USB2_REFCLK") (pinfunction "REFCLK") (pintype "input"))
    (pad "24" smd roundrect (at -1.25 -1.938 270) (size 0.25 0.825) (layers "F.Cu" "F.Paste" "F.Mask") (roundrect_rratio 0.25)
      (net 668 "Net-(U23-RBIAS)") (pinfunction "RBIAS") (pintype "passive"))
    (pad "25" smd rect (at 0 0 270) (size 2.6 2.6) (layers "F.Cu" "F.Mask")
      (net 1 "GND") (pinfunction "GND") (pintype "power_in"))
  )
	(footprint "kria-k26-devboard-footprints:R_0402_1005Metric" (layer "F.Cu")
    (at 142.27 142.56 180)
    (descr "Resistor SMD 0402")
    (tags "resistor SMD 0402")
    (property "Author" "Antmicro")
    (property "License" "Apache-2.0")
    (property "MPN" "CR0402-FX-5111GLF")
    (property "Manufacturer" "Bourns")
    (property "Sheetfile" "debug.kicad_sch")
    (property "Sheetname" "Debug and JTAG")
    (property "Tolerance" "1%")
    (property "Val" "5k11")
    (property "ki_description" "5k11 resistor in 0402 package with 1% tolerance")
    (attr smd)
    (fp_text reference "R99" (at 1.18 0.59 180) (layer "F.SilkS")
        (effects (font (size 0.7 0.7) (thickness 0.15)) (justify left bottom))
    )
    (fp_text value "R_5k11_0402" (at 0 1.4 180) (layer "F.Fab") hide
        (effects (font (size 0.7 0.7) (thickness 0.15)) (justify left bottom))
    )
    (fp_text user "Author: Antmicro" (at -0.95 4.169 180) (layer "F.Fab") hide
        (effects (font (size 0.7 0.7) (thickness 0.15)) (justify left bottom))
    )
    (fp_text user "${REFERENCE}" (at -0.95 3.168 180) (layer "F.Fab") hide
        (effects (font (size 0.7 0.7) (thickness 0.15)) (justify left bottom))
    )
    (fp_text user "License: Apache-2.0" (at -0.95 5.169 180) (layer "F.Fab") hide
        (effects (font (size 0.7 0.7) (thickness 0.15)) (justify left bottom))
    )
    (fp_rect (start -0.93 -0.47) (end 0.93 0.47)
      (stroke (width 0.05) (type solid)) (fill none) (layer "F.CrtYd"))
    (fp_rect (start -0.5 -0.25) (end 0.5 0.25)
      (stroke (width 0.15) (type solid)) (fill none) (layer "F.Fab"))
    (pad "1" smd roundrect (at -0.485 0 180) (size 0.59 0.64) (layers "F.Cu" "F.Paste" "F.Mask") (roundrect_rratio 0.25)
      (net 354 "Net-(J8-CC_{1})") (pintype "passive"))
    (pad "2" smd roundrect (at 0.485 0 180) (size 0.59 0.64) (layers "F.Cu" "F.Paste" "F.Mask") (roundrect_rratio 0.25)
      (net 1 "GND") (pintype "passive"))
  )
	(footprint "kria-k26-devboard-footprints:C_0402_1005Metric" (layer "F.Cu")
    (at 130.025 75.11 -90)
    (descr "Capacitor SMD 0402")
    (tags "capacitor SMD 0402")
    (property "Author" "Antmicro")
    (property "Dielectric" "X5R")
    (property "License" "Apache-2.0")
    (property "MPN" "GRM155R61H104KE14D")
    (property "Manufacturer" "Murata")
    (property "Sheetfile" "usb.kicad_sch")
    (property "Sheetname" "USB")
    (property "Val" "100n")
    (property "Voltage" "50V")
    (property "ki_description" " ")
    (attr smd)
    (fp_text reference "C68" (at 3.07 -0.405 -90) (layer "F.SilkS")
        (effects (font (size 0.7 0.7) (thickness 0.15)) (justify left bottom))
    )
    (fp_text value "C_100n_0402" (at 0 1.4 -90) (layer "F.Fab") hide
        (effects (font (size 0.7 0.7) (thickness 0.15)) (justify left bottom))
    )
    (fp_text user "Author: Antmicro" (at -0.932 4.17 -90) (layer "F.Fab") hide
        (effects (font (size 0.7 0.7) (thickness 0.15)) (justify left bottom))
    )
    (fp_text user "${REFERENCE}" (at -0.932 3.168 -90) (layer "F.Fab") hide
        (effects (font (size 0.7 0.7) (thickness 0.15)) (justify left bottom))
    )
    (fp_text user "License: Apache-2.0" (at -0.932 5.17 -90) (layer "F.Fab") hide
        (effects (font (size 0.7 0.7) (thickness 0.15)) (justify left bottom))
    )
    (fp_rect (start -0.94 -0.47) (end 0.94 0.47)
      (stroke (width 0.05) (type solid)) (fill none) (layer "F.CrtYd"))
    (fp_rect (start -0.499 -0.249) (end 0.499 0.249)
      (stroke (width 0.15) (type solid)) (fill none) (layer "F.Fab"))
    (pad "1" smd roundrect (at -0.484 0 270) (size 0.59 0.64) (layers "F.Cu" "F.Paste" "F.Mask") (roundrect_rratio 0.25)
      (net 280 "/USB/USB2_TX_C_N") (pintype "passive"))
    (pad "2" smd roundrect (at 0.484 0 270) (size 0.59 0.64) (layers "F.Cu" "F.Paste" "F.Mask") (roundrect_rratio 0.25)
      (net 62 "/USB/USB2_TX_N") (pintype "passive"))
  )
)
